(kicad_pcb
	(version 20260206)
	(generator "pcbnew")
	(generator_version "10.0")
	(general
		(thickness 1.6)
		(legacy_teardrops no)
	)
	(paper "A4")
	(title_block
		(title "timecard-production-celestica-r4006 — R4006-B0001-02_R01.brd")
		(comment 1 "Time Appliance Project (Time Card) / footprints 63-66 of 1113")
	)
	(layers
		(0 "F.Cu" signal "TOP")
		(4 "In1.Cu" signal "L02_GND1")
		(6 "In2.Cu" signal "L03_SIG1")
		(8 "In3.Cu" signal "L04_GND2")
		(10 "In4.Cu" signal "L05_VCC1")
		(12 "In5.Cu" signal "L06_VCC2")
		(14 "In6.Cu" signal "L07_GND3")
		(16 "In7.Cu" signal "L08_SIG2")
		(18 "In8.Cu" signal "L09_GND4")
		(2 "B.Cu" signal "BOTTOM")
		(9 "F.Adhes" user "F.Adhesive")
		(11 "B.Adhes" user "B.Adhesive")
		(13 "F.Paste" user "Package Geometry/Pastemask Top")
		(15 "B.Paste" user "Package Geometry/Pastemask Bottom")
		(5 "F.SilkS" user "Ref Des/Silkscreen Top")
		(7 "B.SilkS" user "Ref Des/Silkscreen Bottom")
		(1 "F.Mask" user "Board Geometry/Soldermask Top")
		(3 "B.Mask" user "Board Geometry/Soldermask Bottom")
		(17 "Dwgs.User" user "User.Drawings")
		(19 "Cmts.User" user "User.Comments")
		(21 "Eco1.User" user "User.Eco1")
		(23 "Eco2.User" user "User.Eco2")
		(25 "Edge.Cuts" user "Board Geometry/Outline")
		(27 "Margin" user)
		(31 "F.CrtYd" user "Package Geometry/Place Bound Top")
		(29 "B.CrtYd" user "Package Geometry/Place Bound Bottom")
		(35 "F.Fab" user "Ref Des/Assembly Top")
		(33 "B.Fab" user "Ref Des/Assembly Bottom")
	)
	(footprint ""
		(layer "F.Cu")
		(at 80.772 -65.2526 180)
		(property "Reference" "R305"
			(at 10.287 19.16303 0)
			(unlocked yes)
			(layer "F.SilkS")
			(effects
				(font
					(size 0.7874 0.5842)
					(thickness 0.1524)
				)
			)
		)
		(property "Value" "VAL*"
			(at 0.02032 2.13233 180)
			(unlocked yes)
			(layer "F.Fab")
			(hide yes)
			(effects
				(font
					(size 0.7874 0.5842)
					(thickness 0.1524)
				)
			)
		)
		(property "Device Type" "RESISTOR-G155-11001-01,1KOHM,1%"
			(at 0.008382 1.210564 180)
			(unlocked yes)
			(layer "F.Fab")
			(hide yes)
			(effects
				(font
					(size 0.7874 0.5842)
					(thickness 0.1524)
				)
			)
		)
		(property "User Part Number" "PARTNUM*"
			(at 0.02032 4.024884 180)
			(unlocked yes)
			(layer "Cmts.User")
			(hide yes)
			(effects
				(font
					(size 0.7874 0.5842)
					(thickness 0.1524)
				)
			)
		)
		(property "Tolerance" "TOL*"
			(at 0.044704 3.05435 180)
			(unlocked yes)
			(layer "Cmts.User")
			(hide yes)
			(effects
				(font
					(size 0.7874 0.5842)
					(thickness 0.1524)
				)
			)
		)
		(duplicate_pad_numbers_are_jumpers no)
		(fp_line
			(start 1.143 0.5588)
			(end 1.143 -0.5588)
			(stroke
				(width 0.1)
				(type default)
			)
			(layer "F.SilkS")
		)
		(fp_line
			(start 1.143 -0.5588)
			(end -1.143 -0.5588)
			(stroke
				(width 0.1)
				(type default)
			)
			(layer "F.SilkS")
		)
		(fp_line
			(start -1.143 0.5588)
			(end 1.143 0.5588)
			(stroke
				(width 0.1)
				(type default)
			)
			(layer "F.SilkS")
		)
		(fp_line
			(start -1.143 -0.5588)
			(end -1.143 0.5588)
			(stroke
				(width 0.1)
				(type default)
			)
			(layer "F.SilkS")
		)
		(fp_rect
			(start 1.143 -0.5588)
			(end -1.143 0.5588)
			(stroke
				(width 0)
				(type default)
			)
			(fill no)
			(layer "F.CrtYd")
		)
		(fp_line
			(start 0.508 0.3048)
			(end 0.508 -0.3048)
			(stroke
				(width 0.1)
				(type default)
			)
			(layer "F.Fab")
		)
		(fp_line
			(start 0.508 -0.3048)
			(end -0.508 -0.3048)
			(stroke
				(width 0.1)
				(type default)
			)
			(layer "F.Fab")
		)
		(fp_line
			(start -0.508 0.3048)
			(end 0.508 0.3048)
			(stroke
				(width 0.1)
				(type default)
			)
			(layer "F.Fab")
		)
		(fp_line
			(start -0.508 -0.3048)
			(end -0.508 0.3048)
			(stroke
				(width 0.1)
				(type default)
			)
			(layer "F.Fab")
		)
		(pad "1" smd rect
			(at -0.5334 0 180)
			(size 0.7112 0.6096)
			(layers "F.Cu" "F.Mask" "F.Paste")
			(net "UNNAMED_9_BNO080LGA28_I29_PS0")
		)
		(pad "2" smd rect
			(at 0.5334 0 180)
			(size 0.7112 0.6096)
			(layers "F.Cu" "F.Mask" "F.Paste")
			(net "SG")
		)
		(zone
			(layer "F.Cu")
			(hatch none 0.5)
			(connect_pads
				(clearance 0)
			)
			(min_thickness 0.25)
			(keepout
				(tracks allowed)
				(vias not_allowed)
				(pads allowed)
				(copperpour not_allowed)
				(footprints allowed)
			)
			(placement
				(enabled no)
				(sheetname "")
			)
			(fill
				(thermal_gap 0.5)
				(thermal_bridge_width 0.5)
				(island_removal_mode 0)
			)
			(polygon
				(pts
					(xy 80.6958 -64.9478) (xy 80.8482 -64.9478) (xy 80.8482 -65.5574) (xy 80.6958 -65.5574)
				)
			)
		)
	)
	(footprint ""
		(layer "F.Cu")
		(at 43.815 -73.66 180)
		(property "Reference" "C307"
			(at -0.635 -1.18237 0)
			(unlocked yes)
			(layer "F.SilkS")
			(effects
				(font
					(size 0.7874 0.5842)
					(thickness 0.1524)
				)
			)
		)
		(property "Value" "VAL*"
			(at 0.193548 2.13614 180)
			(unlocked yes)
			(layer "F.Fab")
			(hide yes)
			(effects
				(font
					(size 0.7874 0.5842)
					(thickness 0.1524)
				)
			)
		)
		(property "User Part Number" "PARTNUM*"
			(at 0.216154 4.185666 180)
			(unlocked yes)
			(layer "Cmts.User")
			(hide yes)
			(effects
				(font
					(size 0.7874 0.5842)
					(thickness 0.1524)
				)
			)
		)
		(property "Device Type" "CAPACITOR-G104-0B103-EK,0.01UFA"
			(at 0.184404 1.180592 180)
			(unlocked yes)
			(layer "F.Fab")
			(hide yes)
			(effects
				(font
					(size 0.7874 0.5842)
					(thickness 0.1524)
				)
			)
		)
		(property "Tolerance" "TOL*"
			(at 0.216154 3.1496 180)
			(unlocked yes)
			(layer "Cmts.User")
			(hide yes)
			(effects
				(font
					(size 0.7874 0.5842)
					(thickness 0.1524)
				)
			)
		)
		(duplicate_pad_numbers_are_jumpers no)
		(fp_line
			(start 0.671322 0.4445)
			(end -0.671322 0.4445)
			(stroke
				(width 0.1)
				(type default)
			)
			(layer "F.SilkS")
		)
		(fp_line
			(start 0.671322 -0.4445)
			(end 0.671322 0.4445)
			(stroke
				(width 0.1)
				(type default)
			)
			(layer "F.SilkS")
		)
		(fp_line
			(start -0.671322 0.4445)
			(end -0.671322 -0.4445)
			(stroke
				(width 0.1)
				(type default)
			)
			(layer "F.SilkS")
		)
		(fp_line
			(start -0.671322 -0.4445)
			(end 0.671322 -0.4445)
			(stroke
				(width 0.1)
				(type default)
			)
			(layer "F.SilkS")
		)
		(fp_rect
			(start -0.671322 0.4445)
			(end 0.671322 -0.4445)
			(stroke
				(width 0)
				(type default)
			)
			(fill no)
			(layer "F.CrtYd")
		)
		(fp_line
			(start 0.31496 0.1651)
			(end 0.31496 -0.1651)
			(stroke
				(width 0.1)
				(type default)
			)
			(layer "F.Fab")
		)
		(fp_line
			(start 0.31496 -0.1651)
			(end -0.31496 -0.1651)
			(stroke
				(width 0.1)
				(type default)
			)
			(layer "F.Fab")
		)
		(fp_line
			(start -0.31496 0.1651)
			(end 0.31496 0.1651)
			(stroke
				(width 0.1)
				(type default)
			)
			(layer "F.Fab")
		)
		(fp_line
			(start -0.31496 -0.1651)
			(end -0.31496 0.1651)
			(stroke
				(width 0.1)
				(type default)
			)
			(layer "F.Fab")
		)
		(pad "1" smd rect
			(at -0.264922 0 180)
			(size 0.3048 0.381)
			(layers "F.Cu" "F.Mask" "F.Paste")
			(net "UNNAMED_525_CAPACITOR_I18_1")
		)
		(pad "2" smd rect
			(at 0.264922 0 180)
			(size 0.3048 0.381)
			(layers "F.Cu" "F.Mask" "F.Paste")
			(net "SG")
		)
		(zone
			(layer "F.Cu")
			(hatch none 0.5)
			(connect_pads
				(clearance 0)
			)
			(min_thickness 0.25)
			(keepout
				(tracks not_allowed)
				(vias allowed)
				(pads allowed)
				(copperpour not_allowed)
				(footprints allowed)
			)
			(placement
				(enabled no)
				(sheetname "")
			)
			(fill
				(thermal_gap 0.5)
				(thermal_bridge_width 0.5)
				(island_removal_mode 0)
			)
			(polygon
				(pts
					(xy 43.927522 -73.8505) (xy 43.702478 -73.8505) (xy 43.702478 -73.4695) (xy 43.927522 -73.4695)
				)
			)
		)
		(zone
			(layer "F.Cu")
			(hatch none 0.5)
			(connect_pads
				(clearance 0)
			)
			(min_thickness 0.25)
			(keepout
				(tracks allowed)
				(vias not_allowed)
				(pads allowed)
				(copperpour not_allowed)
				(footprints allowed)
			)
			(placement
				(enabled no)
				(sheetname "")
			)
			(fill
				(thermal_gap 0.5)
				(thermal_bridge_width 0.5)
				(island_removal_mode 0)
			)
			(polygon
				(pts
					(xy 43.927522 -73.4695) (xy 43.927522 -73.8505) (xy 43.702478 -73.8505) (xy 43.702478 -73.4695)
				)
			)
		)
	)
	(footprint ""
		(layer "F.Cu")
		(at 119.761 -19.939)
		(property "Reference" "R475"
			(at -0.127 1.18237 0)
			(unlocked yes)
			(layer "F.SilkS")
			(effects
				(font
					(size 0.7874 0.5842)
					(thickness 0.1524)
				)
			)
		)
		(property "Value" "VAL*"
			(at 0.02032 2.13233 0)
			(unlocked yes)
			(layer "F.Fab")
			(hide yes)
			(effects
				(font
					(size 0.7874 0.5842)
					(thickness 0.1524)
				)
			)
		)
		(property "Tolerance" "TOL*"
			(at 0.044704 3.05435 0)
			(unlocked yes)
			(layer "Cmts.User")
			(hide yes)
			(effects
				(font
					(size 0.7874 0.5842)
					(thickness 0.1524)
				)
			)
		)
		(property "User Part Number" "PARTNUM*"
			(at 0.02032 4.024884 0)
			(unlocked yes)
			(layer "Cmts.User")
			(hide yes)
			(effects
				(font
					(size 0.7874 0.5842)
					(thickness 0.1524)
				)
			)
		)
		(property "Device Type" "RESISTOR-G155-11003-01,100KOHMA"
			(at 0.008382 1.210564 0)
			(unlocked yes)
			(layer "F.Fab")
			(hide yes)
			(effects
				(font
					(size 0.7874 0.5842)
					(thickness 0.1524)
				)
			)
		)
		(duplicate_pad_numbers_are_jumpers no)
		(fp_line
			(start -1.143 -0.5588)
			(end -1.143 0.5588)
			(stroke
				(width 0.1)
				(type default)
			)
			(layer "F.SilkS")
		)
		(fp_line
			(start -1.143 0.5588)
			(end 1.143 0.5588)
			(stroke
				(width 0.1)
				(type default)
			)
			(layer "F.SilkS")
		)
		(fp_line
			(start 1.143 -0.5588)
			(end -1.143 -0.5588)
			(stroke
				(width 0.1)
				(type default)
			)
			(layer "F.SilkS")
		)
		(fp_line
			(start 1.143 0.5588)
			(end 1.143 -0.5588)
			(stroke
				(width 0.1)
				(type default)
			)
			(layer "F.SilkS")
		)
		(fp_poly
			(pts
				(xy -1.143 0.5588) (xy 1.143 0.5588) (xy 1.143 -0.5588) (xy -1.143 -0.5588)
			)
			(stroke
				(width 0)
				(type default)
			)
			(fill no)
			(layer "F.CrtYd")
		)
		(fp_line
			(start -0.508 -0.3048)
			(end -0.508 0.3048)
			(stroke
				(width 0.1)
				(type default)
			)
			(layer "F.Fab")
		)
		(fp_line
			(start -0.508 0.3048)
			(end 0.508 0.3048)
			(stroke
				(width 0.1)
				(type default)
			)
			(layer "F.Fab")
		)
		(fp_line
			(start 0.508 -0.3048)
			(end -0.508 -0.3048)
			(stroke
				(width 0.1)
				(type default)
			)
			(layer "F.Fab")
		)
		(fp_line
			(start 0.508 0.3048)
			(end 0.508 -0.3048)
			(stroke
				(width 0.1)
				(type default)
			)
			(layer "F.Fab")
		)
		(pad "1" smd rect
			(at -0.5334 0)
			(size 0.7112 0.6096)
			(layers "F.Cu" "F.Mask" "F.Paste")
			(net "XP3R3V_FPGA")
		)
		(pad "2" smd rect
			(at 0.5334 0)
			(size 0.7112 0.6096)
			(layers "F.Cu" "F.Mask" "F.Paste")
			(net "FPGA_PCA9546_I2C_SCL")
		)
		(zone
			(layer "F.Cu")
			(hatch none 0.5)
			(connect_pads
				(clearance 0)
			)
			(min_thickness 0.25)
			(keepout
				(tracks not_allowed)
				(vias allowed)
				(pads allowed)
				(copperpour not_allowed)
				(footprints allowed)
			)
			(placement
				(enabled no)
				(sheetname "")
			)
			(fill
				(thermal_gap 0.5)
				(thermal_bridge_width 0.5)
				(island_removal_mode 0)
			)
			(polygon
				(pts
					(xy 119.6848 -19.6342) (xy 119.8372 -19.6342) (xy 119.8372 -20.2438) (xy 119.6848 -20.2438)
				)
			)
		)
		(zone
			(layer "F.Cu")
			(hatch none 0.5)
			(connect_pads
				(clearance 0)
			)
			(min_thickness 0.25)
			(keepout
				(tracks allowed)
				(vias not_allowed)
				(pads allowed)
				(copperpour not_allowed)
				(footprints allowed)
			)
			(placement
				(enabled no)
				(sheetname "")
			)
			(fill
				(thermal_gap 0.5)
				(thermal_bridge_width 0.5)
				(island_removal_mode 0)
			)
			(polygon
				(pts
					(xy 119.6848 -19.6342) (xy 119.8372 -19.6342) (xy 119.8372 -20.2438) (xy 119.6848 -20.2438)
				)
			)
		)
	)
	(footprint ""
		(layer "F.Cu")
		(at 94.234 -68.834)
		(property "Reference" "R167"
			(at -28.067 -19.39163 0)
			(unlocked yes)
			(layer "F.SilkS")
			(effects
				(font
					(size 0.7874 0.5842)
					(thickness 0.1524)
				)
			)
		)
		(property "Value" "VAL*"
			(at 0.02032 2.13233 0)
			(unlocked yes)
			(layer "F.Fab")
			(hide yes)
			(effects
				(font
					(size 0.7874 0.5842)
					(thickness 0.1524)
				)
			)
		)
		(property "Tolerance" "TOL*"
			(at 0.044704 3.05435 0)
			(unlocked yes)
			(layer "Cmts.User")
			(hide yes)
			(effects
				(font
					(size 0.7874 0.5842)
					(thickness 0.1524)
				)
			)
		)
		(property "User Part Number" "PARTNUM*"
			(at 0.02032 4.024884 0)
			(unlocked yes)
			(layer "Cmts.User")
			(hide yes)
			(effects
				(font
					(size 0.7874 0.5842)
					(thickness 0.1524)
				)
			)
		)
		(property "Device Type" "RESISTOR-G155-14701-01,4.7KOHMA"
			(at 0.008382 1.210564 0)
			(unlocked yes)
			(layer "F.Fab")
			(hide yes)
			(effects
				(font
					(size 0.7874 0.5842)
					(thickness 0.1524)
				)
			)
		)
		(duplicate_pad_numbers_are_jumpers no)
		(fp_line
			(start -1.143 -0.5588)
			(end -1.143 0.5588)
			(stroke
				(width 0.1)
				(type default)
			)
			(layer "F.SilkS")
		)
		(fp_line
			(start -1.143 0.5588)
			(end 1.143 0.5588)
			(stroke
				(width 0.1)
				(type default)
			)
			(layer "F.SilkS")
		)
		(fp_line
			(start 1.143 -0.5588)
			(end -1.143 -0.5588)
			(stroke
				(width 0.1)
				(type default)
			)
			(layer "F.SilkS")
		)
		(fp_line
			(start 1.143 0.5588)
			(end 1.143 -0.5588)
			(stroke
				(width 0.1)
				(type default)
			)
			(layer "F.SilkS")
		)
		(fp_poly
			(pts
				(xy -1.143 0.5588) (xy 1.143 0.5588) (xy 1.143 -0.5588) (xy -1.143 -0.5588)
			)
			(stroke
				(width 0)
				(type default)
			)
			(fill no)
			(layer "F.CrtYd")
		)
		(fp_line
			(start -0.508 -0.3048)
			(end -0.508 0.3048)
			(stroke
				(width 0.1)
				(type default)
			)
			(layer "F.Fab")
		)
		(fp_line
			(start -0.508 0.3048)
			(end 0.508 0.3048)
			(stroke
				(width 0.1)
				(type default)
			)
			(layer "F.Fab")
		)
		(fp_line
			(start 0.508 -0.3048)
			(end -0.508 -0.3048)
			(stroke
				(width 0.1)
				(type default)
			)
			(layer "F.Fab")
		)
		(fp_line
			(start 0.508 0.3048)
			(end 0.508 -0.3048)
			(stroke
				(width 0.1)
				(type default)
			)
			(layer "F.Fab")
		)
		(pad "1" smd rect
			(at -0.5334 0)
			(size 0.7112 0.6096)
			(layers "F.Cu" "F.Mask" "F.Paste")
			(net "XP3R3V_FPGA")
		)
		(pad "2" smd rect
			(at 0.5334 0)
			(size 0.7112 0.6096)
			(layers "F.Cu" "F.Mask" "F.Paste")
			(net "FPGA_IN_RST_DLY_N")
		)
		(zone
			(layer "F.Cu")
			(hatch none 0.5)
			(connect_pads
				(clearance 0)
			)
			(min_thickness 0.25)
			(keepout
				(tracks allowed)
				(vias not_allowed)
				(pads allowed)
				(copperpour not_allowed)
				(footprints allowed)
			)
			(placement
				(enabled no)
				(sheetname "")
			)
			(fill
				(thermal_gap 0.5)
				(thermal_bridge_width 0.5)
				(island_removal_mode 0)
			)
			(polygon
				(pts
					(xy 94.1578 -68.5292) (xy 94.3102 -68.5292) (xy 94.3102 -69.1388) (xy 94.1578 -69.1388)
				)
			)
		)
		(zone
			(layer "F.Cu")
			(hatch none 0.5)
			(connect_pads
				(clearance 0)
			)
			(min_thickness 0.25)
			(keepout
				(tracks not_allowed)
				(vias allowed)
				(pads allowed)
				(copperpour not_allowed)
				(footprints allowed)
			)
			(placement
				(enabled no)
				(sheetname "")
			)
			(fill
				(thermal_gap 0.5)
				(thermal_bridge_width 0.5)
				(island_removal_mode 0)
			)
			(polygon
				(pts
					(xy 94.1578 -68.5292) (xy 94.3102 -68.5292) (xy 94.3102 -69.1388) (xy 94.1578 -69.1388)
				)
			)
		)
	)
)
